# T6G (Grand Teton) — schematic netlist excerpt (pin names and nets, part order shuffled) for the footprints in the layout excerpt that follows; sources: Cadence DE-HDL packaged netlist, KiCad conversion of 04192023_DAF0TMB3IC0_F0TG_MB_C_brd_V02_OCP.brd

PR202  Q_RES  8.87K 1% EMPTY  pkg 0402LF  page 213 : A = GND ; B = PVDDCR_CPU0_P1_LSET5
C70  Q_CAP  0.1UF 25V 10% X7R  pkg 0402  page 241 : A = HPDB_HSC_PWRGD_ISO ; B = GND

(kicad_pcb
	(version 20260206)
	(generator "pcbnew")
	(generator_version "10.0")
	(general
		(thickness 1.6)
		(legacy_teardrops no)
	)
	(paper "A4")
	(title_block
		(title "04192023_DAF0TMB3IC0_F0TG_MB_C_brd_V02_OCP.brd")
		(comment 1 "Grand Teton / footprints 1081-1082 of 8354")
	)
	(layers
		(0 "F.Cu" signal "TOP")
		(4 "In1.Cu" signal "GND")
		(6 "In2.Cu" signal "IN1")
		(8 "In3.Cu" signal "GND1")
		(10 "In4.Cu" signal "IN2")
		(12 "In5.Cu" signal "GND2")
		(14 "In6.Cu" signal "IN3")
		(16 "In7.Cu" signal "GND3")
		(18 "In8.Cu" signal "VCC")
		(20 "In9.Cu" signal "VCC1")
		(22 "In10.Cu" signal "GND4")
		(24 "In11.Cu" signal "IN4")
		(26 "In12.Cu" signal "GND5")
		(28 "In13.Cu" signal "IN5")
		(30 "In14.Cu" signal "GND6")
		(32 "In15.Cu" signal "IN6")
		(34 "In16.Cu" signal "GND7")
		(2 "B.Cu" signal "BOTTOM")
		(9 "F.Adhes" user "F.Adhesive")
		(11 "B.Adhes" user "B.Adhesive")
		(13 "F.Paste" user "Package Geometry/Pastemask Top")
		(15 "B.Paste" user "Package Geometry/Pastemask Bottom")
		(5 "F.SilkS" user "Ref Des/Silkscreen Top")
		(7 "B.SilkS" user "Ref Des/Silkscreen Bottom")
		(1 "F.Mask" user "Board Geometry/Soldermask Top")
		(3 "B.Mask" user "Board Geometry/Soldermask Bottom")
		(17 "Dwgs.User" user "User.Drawings")
		(19 "Cmts.User" user "User.Comments")
		(21 "Eco1.User" user "User.Eco1")
		(23 "Eco2.User" user "User.Eco2")
		(25 "Edge.Cuts" user "Board Geometry/Outline")
		(27 "Margin" user)
		(31 "F.CrtYd" user "Package Geometry/Place Bound Top")
		(29 "B.CrtYd" user "Package Geometry/Place Bound Bottom")
		(35 "F.Fab" user "Ref Des/Assembly Top")
		(33 "B.Fab" user "Ref Des/Assembly Bottom")
	)
	(footprint ""
		(layer "F.Cu")
		(at 75.265534 -172.414184)
		(property "Reference" "PR202"
			(at 0 0 0)
			(layer "F.SilkS")
			(hide yes)
			(effects
				(font
					(size 1.27 1.27)
				)
			)
		)
		(property "Value" ""
			(at 0 0 0)
			(layer "F.Fab")
			(effects
				(font
					(size 1.27 1.27)
				)
			)
		)
		(duplicate_pad_numbers_are_jumpers no)
		(fp_line
			(start -0.7874 -0.4064)
			(end 0.7874 -0.4064)
			(stroke
				(width 0.1524)
				(type default)
			)
			(layer "F.SilkS")
		)
		(fp_line
			(start -0.7874 0.4064)
			(end -0.7874 -0.4064)
			(stroke
				(width 0.1524)
				(type default)
			)
			(layer "F.SilkS")
		)
		(fp_line
			(start 0.7874 -0.4064)
			(end 0.7874 0.4064)
			(stroke
				(width 0.1524)
				(type default)
			)
			(layer "F.SilkS")
		)
		(fp_line
			(start 0.7874 0.4064)
			(end -0.7874 0.4064)
			(stroke
				(width 0.1524)
				(type default)
			)
			(layer "F.SilkS")
		)
		(fp_line
			(start -0.67945 -0.305054)
			(end -0.12065 -0.305054)
			(stroke
				(width 0.1)
				(type default)
			)
			(layer "F.Fab")
		)
		(fp_line
			(start -0.67945 0.3048)
			(end -0.67945 -0.305054)
			(stroke
				(width 0.1)
				(type default)
			)
			(layer "F.Fab")
		)
		(fp_line
			(start -0.12065 -0.305054)
			(end -0.12065 -0.2794)
			(stroke
				(width 0.1)
				(type default)
			)
			(layer "F.Fab")
		)
		(fp_line
			(start -0.12065 -0.2794)
			(end 0.12065 -0.2794)
			(stroke
				(width 0.1)
				(type default)
			)
			(layer "F.Fab")
		)
		(fp_line
			(start -0.12065 0.2794)
			(end -0.12065 0.3048)
			(stroke
				(width 0.1)
				(type default)
			)
			(layer "F.Fab")
		)
		(fp_line
			(start -0.12065 0.3048)
			(end -0.67945 0.3048)
			(stroke
				(width 0.1)
				(type default)
			)
			(layer "F.Fab")
		)
		(fp_line
			(start 0.120396 0.2794)
			(end -0.12065 0.2794)
			(stroke
				(width 0.1)
				(type default)
			)
			(layer "F.Fab")
		)
		(fp_line
			(start 0.120396 0.3048)
			(end 0.120396 0.2794)
			(stroke
				(width 0.1)
				(type default)
			)
			(layer "F.Fab")
		)
		(fp_line
			(start 0.12065 -0.3048)
			(end 0.67945 -0.3048)
			(stroke
				(width 0.1)
				(type default)
			)
			(layer "F.Fab")
		)
		(fp_line
			(start 0.12065 -0.2794)
			(end 0.12065 -0.3048)
			(stroke
				(width 0.1)
				(type default)
			)
			(layer "F.Fab")
		)
		(fp_line
			(start 0.67945 -0.3048)
			(end 0.67945 0.3048)
			(stroke
				(width 0.1)
				(type default)
			)
			(layer "F.Fab")
		)
		(fp_line
			(start 0.67945 0.3048)
			(end 0.120396 0.3048)
			(stroke
				(width 0.1)
				(type default)
			)
			(layer "F.Fab")
		)
		(pad "1" smd circle
			(at -0.40005 0)
			(size 0 0)
			(layers "F.Cu" "F.Mask" "F.Paste")
			(net "GND")
		)
		(pad "2" smd circle
			(at 0.40005 0)
			(size 0 0)
			(layers "F.Cu" "F.Mask" "F.Paste")
			(net "PVDDCR_CPU0_P1_LSET5")
		)
	)
	(footprint ""
		(layer "F.Cu")
		(at 278.006556 -436.223664 -90)
		(property "Reference" "C70"
			(at 0 0 270)
			(layer "F.SilkS")
			(hide yes)
			(effects
				(font
					(size 1.27 1.27)
				)
			)
		)
		(property "Value" ""
			(at 0 0 270)
			(layer "F.Fab")
			(effects
				(font
					(size 1.27 1.27)
				)
			)
		)
		(duplicate_pad_numbers_are_jumpers no)
		(fp_line
			(start -0.7874 0.4064)
			(end -0.7874 -0.4064)
			(stroke
				(width 0.1524)
				(type default)
			)
			(layer "F.SilkS")
		)
		(fp_line
			(start 0.7874 0.4064)
			(end -0.7874 0.4064)
			(stroke
				(width 0.1524)
				(type default)
			)
			(layer "F.SilkS")
		)
		(fp_line
			(start -0.7874 -0.4064)
			(end 0.7874 -0.4064)
			(stroke
				(width 0.1524)
				(type default)
			)
			(layer "F.SilkS")
		)
		(fp_line
			(start 0.7874 -0.4064)
			(end 0.7874 0.4064)
			(stroke
				(width 0.1524)
				(type default)
			)
			(layer "F.SilkS")
		)
		(fp_line
			(start -0.67945 0.3048)
			(end -0.67945 -0.305054)
			(stroke
				(width 0.1)
				(type default)
			)
			(layer "F.Fab")
		)
		(fp_line
			(start -0.12065 0.3048)
			(end -0.67945 0.3048)
			(stroke
				(width 0.1)
				(type default)
			)
			(layer "F.Fab")
		)
		(fp_line
			(start 0.120396 0.3048)
			(end 0.120396 0.2794)
			(stroke
				(width 0.1)
				(type default)
			)
			(layer "F.Fab")
		)
		(fp_line
			(start 0.67945 0.3048)
			(end 0.120396 0.3048)
			(stroke
				(width 0.1)
				(type default)
			)
			(layer "F.Fab")
		)
		(fp_line
			(start -0.12065 0.2794)
			(end -0.12065 0.3048)
			(stroke
				(width 0.1)
				(type default)
			)
			(layer "F.Fab")
		)
		(fp_line
			(start 0.120396 0.2794)
			(end -0.12065 0.2794)
			(stroke
				(width 0.1)
				(type default)
			)
			(layer "F.Fab")
		)
		(fp_line
			(start -0.12065 -0.2794)
			(end 0.12065 -0.2794)
			(stroke
				(width 0.1)
				(type default)
			)
			(layer "F.Fab")
		)
		(fp_line
			(start 0.12065 -0.2794)
			(end 0.12065 -0.3048)
			(stroke
				(width 0.1)
				(type default)
			)
			(layer "F.Fab")
		)
		(fp_line
			(start 0.12065 -0.3048)
			(end 0.67945 -0.3048)
			(stroke
				(width 0.1)
				(type default)
			)
			(layer "F.Fab")
		)
		(fp_line
			(start 0.67945 -0.3048)
			(end 0.67945 0.3048)
			(stroke
				(width 0.1)
				(type default)
			)
			(layer "F.Fab")
		)
		(fp_line
			(start -0.67945 -0.305054)
			(end -0.12065 -0.305054)
			(stroke
				(width 0.1)
				(type default)
			)
			(layer "F.Fab")
		)
		(fp_line
			(start -0.12065 -0.305054)
			(end -0.12065 -0.2794)
			(stroke
				(width 0.1)
				(type default)
			)
			(layer "F.Fab")
		)
		(pad "1" smd circle
			(at -0.40005 0 270)
			(size 0 0)
			(layers "F.Cu" "F.Mask" "F.Paste")
			(net "HPDB_HSC_PWRGD_ISO")
		)
		(pad "2" smd circle
			(at 0.40005 0 270)
			(size 0 0)
			(layers "F.Cu" "F.Mask" "F.Paste")
			(net "GND")
		)
	)
)
